FILE_TYPE = CONNECTIVITY;
{Allegro Design Entry HDL 17.2-2016 S081 (4005846) 1/11/2022}
"PAGE_NUMBER" = 156;
0"NC";
1"P3V3_AUX\g"$PHYS_NET_NAME"P3V3_AUX"CDS_PHYS_NET_NAME"P3V3_AUX"VOLTAGE"3.3";
2"P3V3_AUX\g";
3"P3V3_AUX\g";
4"P3V3_AUX\g";
5"P3V3_AUX\g";
6"P3V3_AUX\g";
7"P3V3_AUX\g";
8"P3V3_AUX\g";
9"P3V3_OCP_V3_2\g";
10"P3V3_AUX\g";
11"GND\g";
12"GND\g";
13"GND\g";
14"GND\g";
15"GND\g";
16"GND\g";
17"GND\g";
18"GND\g";
19"GND\g";
20"GND\g";
21"GND\g";
22"GND\g";
23"GND\g";
24"OCP_V3_2_AUX_PWR_EN"CDS_PHYS_NET_NAME"OCP_V3_2_AUX_PWR_EN";
25"OCP_V3_2_AUX_PWR_EN_R3"CDS_PHYS_NET_NAME"OCP_V3_2_AUX_PWR_EN_R3";
26"FM_SYS_THROTTLE_R_N"CDS_PHYS_NET_NAME"FM_SYS_THROTTLE_R_N";
27"NC_U218_NC1"CDS_PHYS_NET_NAME"NC_U104_NC1";
28"NC_U219_NC1"CDS_PHYS_NET_NAME"NC_U157_NC1";
29"OCP_V3_2_PWRBRK_BUFF_N"CDS_PHYS_NET_NAME"OCP_SFF_PWRBRK_BUFF_N";
30"OCP_V3_2_WAKE_BUFF_R_N"CDS_PHYS_NET_NAME"OCP_SFF_WAKE_BUFF_R_N";
31"RST_PERST3_OCP_V3_2_N"CDS_PHYS_NET_NAME"RST_PERST3_OCP_SFF_N";
32"CLK_50M_NCSI_OCP_V3_2"CDS_PHYS_NET_NAME"CLK_50M_NCSI_OCP_SFF";
33"CLK_50M_NCSI_OCP_V3_2_ISO_R"CDS_PHYS_NET_NAME"CLK_50M_NCSI_OCP_SFF";
34"FB_BMC_ISOLATE1";
35"CLK_50M_NCSI_OCP_V3_2_ISO"CDS_PHYS_NET_NAME"CLK_50M_NCSI_OCP_SFF";
36"RST_SMB_OCP_V3_2_N";
37"RST_HP_OCP_V3_2_R_N";
38"RST_OCP_V3_2_BUF_N"CDS_PHYS_NET_NAME"RST_OCP_V3_1_BUF_N";
39"RST_SMB_SWITCH_N"CDS_PHYS_NET_NAME"RST_SMB_SWITCH_N";
40"PU_OCP_V3_2_WAKE_OE"CDS_PHYS_NET_NAME"PU_OCP_SFF_WAKE_OE";
41"IRQ_LVC3_WAKE_N"CDS_PHYS_NET_NAME"IRQ_LVC3_WAKE_N";
42"IRQ_LVC3_V3_2_WAKE_BUF_N"CDS_PHYS_NET_NAME"IRQ_LVC3_WAKE_BUF_N";
43"OCP_V3_2_WAKE_BUFF_N"CDS_PHYS_NET_NAME"OCP_SFF_WAKE_BUFF_N";
44"IRQ_LVC3_OCP_V3_2_WAKE_N"CDS_PHYS_NET_NAME"IRQ_LVC3_OCP_SFF_WAKE_N";
45"RST_HP_OCP_V3_2_N"CDS_PHYS_NET_NAME"RST_HP_OCP_V3_1_N";
46"RST_PERST0_OCP_V3_2_N"CDS_PHYS_NET_NAME"RST_PERST0_OCP_SFF_N";
47"RST_PERST1_OCP_V3_2_N"CDS_PHYS_NET_NAME"RST_PERST1_OCP_SFF_N";
48"RST_PERST2_OCP_V3_2_N"CDS_PHYS_NET_NAME"RST_PERST2_OCP_SFF_N";
49"OCP_V3_2_PWRBRK_N"CDS_PHYS_NET_NAME"OCP_SFF_PWRBRK_N";
%"UNIVERSAL_GND"
"1","(5050,1200)","0","logical_power","I11";
;
HDL_POWER"GND"
CDS_LIB"logical_power";
"A"13;
%"Q_CAP"
"1","(5050,1425)","2","pure_quanta","I12";
;
PART_NUMBER"CH4104K1B00"
VOLTAGE"25V"
PACK_TYPE"0402"
MATERIAL"X7R"
TOLERANCE"10%"
VALUE"0.1UF"
$LOCATION"C1821"
CDS_LIB"pure_quanta"
CDS_LOCATION"C1821"
$SEC"1"
CDS_SEC"1";
"B"
$PN"2"13;
"A"
$PN"1"5;
%"UNIVERSAL_GND"
"1","(7650,-2100)","0","logical_power","I19";
;
HDL_POWER"GND"
CDS_LIB"logical_power";
"A"18;
%"Q_RES"
"1","(6350,-1775)","0","pure_quanta","I24";
;
PART_NUMBER"CS03322FB03"
VALUE"33.2"
TOLERANCE"1%"
MATERIAL"CHIP"
WATTAGE"1/16W"
PACK_TYPE"0402LF"
$LOCATION"R3185"
CDS_LIB"pure_quanta"
CDS_LOCATION"R3185"
$SEC"1"
CDS_SEC"1";
"B"
$PN"2"30;
"A"
$PN"1"43;
%"UNIVERSAL_POWER"
"1","(5200,-950)","0","logical_power","I25";
;
HDL_POWER"P3V3_AUX"
CDS_LIB"logical_power";
"A"1;
%"UNIVERSAL_GND"
"1","(5200,-1500)","0","logical_power","I26";
;
HDL_POWER"GND"
CDS_LIB"logical_power";
"A"19;
%"Q_CAP"
"1","(5200,-1275)","0","pure_quanta","I27";
;
PART_NUMBER"CH4104K1B00"
PACK_TYPE"0402"
MATERIAL"X7R"
TOLERANCE"10%"
VOLTAGE"25V"
VALUE"0.1UF"
$LOCATION"C1822"
CDS_LIB"pure_quanta"
CDS_LOCATION"C1822"
$SEC"1"
CDS_SEC"1";
"B"
$PN"2"19;
"A"
$PN"1"1;
%"Q_RES"
"2","(6025,-1325)","0","pure_quanta","I28";
;
PART_NUMBER"CS24702FB06"
MATERIAL"CHIP"
WATTAGE"1/16W"
TOLERANCE"1%"
VALUE"4.7K"
PACK_TYPE"0402LF"
$LOCATION"R3184"
CDS_LIB"pure_quanta"
CDS_LOCATION"R3184"
$SEC"1"
CDS_SEC"1";
"A"
$PN"1"2;
"B"
$PN"2"43;
%"UNIVERSAL_POWER"
"1","(6025,-1125)","0","logical_power","I29";
;
HDL_POWER"P3V3_AUX"
CDS_LIB"logical_power";
"A"2;
%"UNIVERSAL_GND"
"1","(5350,-775)","0","logical_power","I30";
;
HDL_POWER"GND"
CDS_LIB"logical_power";
"A"14;
%"74LVC1G07GV"
"1","(5825,-450)","0","pure_quanta","I31";
;
PART_NUMBER"AL1G0007001"
PART_TYPE"SMLF"
MATERIAL"IC"
VALUE"74LVC1G07GV"
$LOCATION"U218"
CDS_LIB"pure_quanta"
NEEDS_NO_SIZE"TRUE"
CDS_LMAN_SYM_OUTLINE"-125,150,125,-150"
CDS_LOCATION"U218"
$SEC"1"
CDS_SEC"1";
"NC1"
$PN"1"27;
"Y"
$PN"4"29;
"GND"
$PN"3"14;
"A"
$PN"2"26;
"VCC"
$PN"5"7;
%"UNIVERSAL_GND"
"1","(6500,-300)","0","logical_power","I32";
;
CDS_LIB"logical_power"
HDL_POWER"GND";
"A"15;
%"Q_CAP"
"1","(6500,-75)","0","pure_quanta","I33";
;
PART_NUMBER"CH4104K1B00"
TOLERANCE"10%"
MATERIAL"X7R"
VALUE"0.1UF"
VOLTAGE"25V"
PACK_TYPE"0402"
$LOCATION"C1823"
CDS_LIB"pure_quanta"
CDS_LOCATION"C1823"
$SEC"1"
CDS_SEC"1";
"B"
$PN"2"15;
"A"
$PN"1"7;
%"UNIVERSAL_GND"
"1","(5375,850)","0","logical_power","I34";
;
CDS_LIB"logical_power"
HDL_POWER"GND";
"A"16;
%"74LVC1G17GW"
"1","(5550,1100)","0","pure_quanta","I35";
;
PART_NUMBER"AL1G0017K01"
MATERIAL"IC"
PART_TYPE"SMLF"
VALUE"74LVC1G17GW"
$LOCATION"U207"
PIN_NAMES_ROTATE"True"
CDS_LMAN_SYM_OUTLINE"-125,150,125,-150"
CDS_LIB"pure_quanta"
SEC_TYPE""
CDS_LOCATION"U207"
SEC"1";
"NC"
$PN"1"0;
"Y"
$PN"4"38;
"GND"
$PN"3"16;
"A"
$PN"2"45;
"VCC"
$PN"5"5;
%"UNIVERSAL_POWER"
"1","(5250,1700)","0","logical_power","I36";
;
HDL_POWER"P3V3_AUX"
CDS_LIB"logical_power";
"A"5;
%"UNIVERSAL_POWER"
"1","(6300,200)","0","logical_power","I37";
;
HDL_POWER"P3V3_AUX"
CDS_LIB"logical_power";
"A"7;
%"Q_RES"
"1","(7000,425)","0","pure_quanta","I38";
;
PART_NUMBER"CS03322FB03"
MATERIAL"CHIP"
WATTAGE"1/16W"
TOLERANCE"1%"
VALUE"33.2"
PACK_TYPE"0402LF"
$LOCATION"R3189"
CDS_LIB"pure_quanta"
CDS_LOCATION"R3189"
$SEC"1"
CDS_SEC"1";
"B"
$PN"2"31;
"A"
$PN"1"38;
%"Q_RES"
"1","(7000,650)","0","pure_quanta","I39";
;
PART_NUMBER"CS03322FB03"
TOLERANCE"1%"
WATTAGE"1/16W"
VALUE"33.2"
PACK_TYPE"0402LF"
MATERIAL"CHIP"
$LOCATION"R3188"
CDS_LIB"pure_quanta"
CDS_LOCATION"R3188"
$SEC"1"
CDS_SEC"1";
"B"
$PN"2"48;
"A"
$PN"1"38;
%"Q_RES"
"1","(7000,875)","0","pure_quanta","I40";
;
PART_NUMBER"CS03322FB03"
MATERIAL"CHIP"
PACK_TYPE"0402LF"
TOLERANCE"1%"
VALUE"33.2"
WATTAGE"1/16W"
$LOCATION"R3187"
CDS_LIB"pure_quanta"
CDS_LOCATION"R3187"
$SEC"1"
CDS_SEC"1";
"B"
$PN"2"47;
"A"
$PN"1"38;
%"Q_RES"
"1","(7000,1100)","0","pure_quanta","I41";
;
PART_NUMBER"CS03322FB03"
MATERIAL"CHIP"
TOLERANCE"1%"
PACK_TYPE"0402LF"
WATTAGE"1/16W"
VALUE"33.2"
$LOCATION"R3186"
CDS_LIB"pure_quanta"
CDS_LOCATION"R3186"
$SEC"1"
CDS_SEC"1";
"B"
$PN"2"46;
"A"
$PN"1"38;
%"Q_RES"
"2","(7200,-175)","0","pure_quanta","I42";
;
PART_NUMBER"CS24702FB06"
VALUE"4.7K"
TOLERANCE"1%"
WATTAGE"1/16W"
PACK_TYPE"0402LF"
MATERIAL"CHIP"
$LOCATION"R3190"
CDS_LIB"pure_quanta"
CDS_LOCATION"R3190"
$SEC"1"
CDS_SEC"1";
"A"
$PN"1"6;
"B"
$PN"2"29;
%"UNIVERSAL_POWER"
"1","(7200,25)","0","logical_power","I43";
;
HDL_POWER"P3V3_AUX"
CDS_LIB"logical_power";
"A"6;
%"Q_RES"
"1","(7750,-550)","0","pure_quanta","I44";
;
PART_NUMBER"CS03322FB03"
PACK_TYPE"0402LF"
MATERIAL"CHIP"
VALUE"33.2"
WATTAGE"1/16W"
TOLERANCE"1%"
$LOCATION"R3191"
CDS_LIB"pure_quanta"
CDS_LOCATION"R3191"
$SEC"1"
CDS_SEC"1";
"B"
$PN"2"49;
"A"
$PN"1"29;
%"UNIVERSAL_POWER"
"1","(8550,-1225)","0","logical_power","I45";
;
HDL_POWER"P3V3_AUX"
CDS_LIB"logical_power";
"A"3;
%"UNIVERSAL_GND"
"1","(8750,-1725)","0","logical_power","I46";
;
HDL_POWER"GND"
CDS_LIB"logical_power";
"A"17;
%"Q_CAP"
"1","(8750,-1500)","0","pure_quanta","I47";
;
PART_NUMBER"CH4104K1B00"
VOLTAGE"25V"
VALUE"0.1UF"
MATERIAL"X7R"
PACK_TYPE"0402"
TOLERANCE"10%"
$LOCATION"C1824"
CDS_LIB"pure_quanta"
CDS_LOCATION"C1824"
$SEC"1"
CDS_SEC"1";
"B"
$PN"2"17;
"A"
$PN"1"3;
%"Q_RES"
"1","(9600,-1875)","0","pure_quanta","I55";
;
PART_NUMBER"CS03322FB03"
PACK_TYPE"0402LF"
VALUE"33.2"
TOLERANCE"1%"
MATERIAL"CHIP"
WATTAGE"1/16W"
$LOCATION"R3193"
CDS_LIB"pure_quanta"
CDS_LOCATION"R3193"
$SEC"1"
CDS_SEC"1";
"B"
$PN"2"41;
"A"
$PN"1"42;
%"Q_RES"
"2","(9300,-1425)","0","pure_quanta","I59";
;
PART_NUMBER"CS24702FB06"
MATERIAL"EMPTY"
PACK_TYPE"0402LF"
TOLERANCE"1%"
VALUE"4.7K"
WATTAGE"1/16W"
$LOCATION"R3192"
CDS_LIB"pure_quanta"
CDS_LOCATION"R3192"
$SEC"1"
CDS_SEC"1";
"A"
$PN"1"8;
"B"
$PN"2"42;
%"Q_RES"
"2","(3400,-1425)","2","pure_quanta","I6";
;
PART_NUMBER"CS31002FB08"
MATERIAL"CHIP"
PACK_TYPE"0402LF"
WATTAGE"1/16W"
TOLERANCE"1%"
VALUE"10K"
$LOCATION"R3182"
CDS_LIB"pure_quanta"
CDS_LOCATION"R3182"
$SEC"1"
CDS_SEC"1";
"A"
$PN"1"9;
"B"
$PN"2"44;
%"UNIVERSAL_POWER"
"1","(9300,-1225)","0","logical_power","I60";
;
HDL_POWER"P3V3_AUX"
CDS_LIB"logical_power";
"A"8;
%"74LVC1G07GV"
"1","(8125,-1775)","0","pure_quanta","I61";
;
PART_NUMBER"AL1G0007001"
VALUE"74LVC1G07GV"
PART_TYPE"SMLF"
MATERIAL"IC"
$LOCATION"U219"
CDS_LIB"pure_quanta"
CDS_LMAN_SYM_OUTLINE"-125,150,125,-150"
NEEDS_NO_SIZE"TRUE"
CDS_LOCATION"U219"
$SEC"1"
CDS_SEC"1";
"NC1"
$PN"1"28;
"Y"
$PN"4"42;
"GND"
$PN"3"18;
"A"
$PN"2"30;
"VCC"
$PN"5"3;
%"UNIVERSAL_GND"
"1","(5700,-2975)","0","logical_power","I64";
;
CDS_LIB"logical_power"
HDL_POWER"GND";
"A"23;
%"Q_CAP"
"1","(5700,-2750)","2","pure_quanta","I65";
;
PART_NUMBER"CH4104K1B00"
VALUE"0.1UF"
VOLTAGE"25V"
MATERIAL"X7R"
PACK_TYPE"0402"
TOLERANCE"10%"
$LOCATION"C1841"
CDS_LIB"pure_quanta"
CDS_LOCATION"C1841"
$SEC"1"
CDS_SEC"1";
"B"
$PN"2"23;
"A"
$PN"1"10;
%"UNIVERSAL_POWER"
"1","(5700,-2450)","0","logical_power","I69";
;
HDL_POWER"P3V3_AUX"
CDS_LIB"logical_power";
"A"10;
%"Q_RES"
"2","(3675,-1425)","0","pure_quanta","I7";
;
PART_NUMBER"CS31002FB08"
MATERIAL"CHIP"
WATTAGE"1/16W"
VALUE"10K"
TOLERANCE"1%"
PACK_TYPE"0402LF"
$LOCATION"R3183"
CDS_LIB"pure_quanta"
CDS_LOCATION"R3183"
$SEC"1"
CDS_SEC"1";
"A"
$PN"1"9;
"B"
$PN"2"40;
%"Q_RES"
"1","(7150,-3175)","0","pure_quanta","I70";
;
PART_NUMBER"CS00002JB13"
VALUE"0"
PACK_TYPE"0402LF"
MATERIAL"CHIP"
TOLERANCE"5%"
WATTAGE"1/16W"
$LOCATION"R3236"
CDS_LIB"pure_quanta"
CDS_LOCATION"R3236"
$SEC"1"
CDS_SEC"1";
"B"
$PN"2"36;
"A"
$PN"1"37;
%"UNIVERSAL_GND"
"1","(6875,-3600)","0","logical_power","I71";
;
CDS_LIB"logical_power"
HDL_POWER"GND";
"A"21;
%"Q_RES"
"2","(6875,-3375)","0","pure_quanta","I72";
;
PART_NUMBER"CS41002FB09"
TOLERANCE"1%"
WATTAGE"1/16W"
MATERIAL"CHIP"
PACK_TYPE"0402LF"
VALUE"100K"
$LOCATION"R3235"
CDS_LIB"pure_quanta"
CDS_LOCATION"R3235"
$SEC"1"
CDS_SEC"1";
"A"
$PN"1"37;
"B"
$PN"2"21;
%"74LVC1G126SE7"
"1","(5925,-3175)","0","pure_quanta","I74";
;
PART_NUMBER"AL1G0126009"
VALUE"74LVC1G126SE-7"
PART_TYPE"SMLF"
MATERIAL"IC"
LOCATION"U225"
NEEDS_NO_SIZE"TRUE"
CDS_LIB"pure_quanta"
CDS_LMAN_SYM_OUTLINE"-100,100,100,-100"
$SEC"1"
CDS_SEC"1";
"OE"
$PN"1"25;
"GND"
$PN"3"22;
"VCC"
$PN"5"10;
"Y"
$PN"4"37;
"A"
$PN"2"39;
%"Q_RES"
"1","(4350,-3225)","0","pure_quanta","I75";
;
PART_NUMBER"CS03322FB03"
PACK_TYPE"0402LF"
WATTAGE"1/16W"
MATERIAL"CHIP"
VALUE"33.2"
TOLERANCE"1%"
$LOCATION"R3234"
CDS_LIB"pure_quanta"
CDS_LOCATION"R3234"
$SEC"1"
CDS_SEC"1";
"B"
$PN"2"25;
"A"
$PN"1"24;
%"UNIVERSAL_GND"
"1","(5925,-3550)","0","logical_power","I78";
;
HDL_POWER"GND"
CDS_LIB"logical_power";
"A"22;
%"74LVC1G126SE7"
"1","(4900,-1775)","0","pure_quanta","I79";
;
PART_NUMBER"AL1G0126009"
PART_TYPE"SMLF"
VALUE"74LVC1G126SE-7"
MATERIAL"IC"
LOCATION"U217"
NEEDS_NO_SIZE"TRUE"
CDS_LMAN_SYM_OUTLINE"-100,100,100,-100"
CDS_LIB"pure_quanta"
$SEC"1"
CDS_SEC"1";
"OE"
$PN"1"40;
"GND"
$PN"3"20;
"VCC"
$PN"5"1;
"Y"
$PN"4"43;
"A"
$PN"2"44;
%"UNIVERSAL_POWER"
"1","(3675,-1075)","0","logical_power","I8";
;
HDL_POWER"P3V3_OCP_V3_2"
CDS_LIB"logical_power";
"A"9;
%"UNIVERSAL_GND"
"1","(4900,-2225)","0","logical_power","I80";
;
CDS_LIB"logical_power"
HDL_POWER"GND";
"A"20;
%"Q_CAP"
"1","(10825,-3200)","0","pure_quanta","I81";
;
PART_NUMBER"CH4104K1B00"
PACK_TYPE"0402"
MATERIAL"X7R"
TOLERANCE"10%"
VOLTAGE"25V"
VALUE"0.1UF"
$LOCATION"C2345"
CDS_LIB"pure_quanta"
CDS_LOCATION"C2345"
$SEC"1"
CDS_SEC"1";
"B"
$PN"2"11;
"A"
$PN"1"4;
%"UNIVERSAL_POWER"
"1","(10625,-2925)","0","logical_power","I82";
;
HDL_POWER"P3V3_AUX"
CDS_LIB"logical_power";
"A"4;
%"UNIVERSAL_GND"
"1","(10825,-3425)","0","logical_power","I84";
;
HDL_POWER"GND"
CDS_LIB"logical_power";
"A"11;
%"UNIVERSAL_GND"
"1","(9750,-3725)","0","logical_power","I86";
;
HDL_POWER"GND"
CDS_LIB"logical_power";
"A"12;
%"Q_RES"
"1","(8625,-3475)","0","pure_quanta","I90";
;
PART_NUMBER"CS00002JB13"
MATERIAL"CHIP"
VALUE"0"
$LOCATION"R4602"
CDS_LIB"pure_quanta"
PACK_TYPE"0402LF"
TOLERANCE"5%"
WATTAGE"1/16W"
CDS_LOCATION"R4602"
$SEC"1"
CDS_SEC"1";
"B"
$PN"2"33;
"A"
$PN"1"35;
%"74LVC1G66GV"
"1","(10175,-3475)","0","pure_quanta","I92";
;
PART_NUMBER"AL001G66000"
MATERIAL"IC"
PART_TYPE"SMLF"
VALUE"74LVC1G66GV"
LOCATION"U321"
PIN_NAMES_ROTATE"True"
CDS_LMAN_SYM_OUTLINE"-150,150,150,-150"
CDS_LIB"pure_quanta"
$SEC"1"
CDS_SEC"1";
"VCC"
$PN"5"4;
"E"
$PN"4"34;
"GND"
$PN"3"12;
"Z"
$PN"2"33;
"Y"
$PN"1"32;
END.
